(kicad_pcb
	(version 20260206)
	(generator "pcbnew")
	(generator_version "10.0")
	(general
		(thickness 1.6)
		(legacy_teardrops no)
	)
	(paper "A4")
	(title_block
		(title "04192023_DAF0TMB3IC0_F0TG_MB_C_brd_V02_OCP.brd")
		(comment 1 "Grand Teton / footprints 2861-2862 of 8354")
	)
	(layers
		(0 "F.Cu" signal "TOP")
		(4 "In1.Cu" signal "GND")
		(6 "In2.Cu" signal "IN1")
		(8 "In3.Cu" signal "GND1")
		(10 "In4.Cu" signal "IN2")
		(12 "In5.Cu" signal "GND2")
		(14 "In6.Cu" signal "IN3")
		(16 "In7.Cu" signal "GND3")
		(18 "In8.Cu" signal "VCC")
		(20 "In9.Cu" signal "VCC1")
		(22 "In10.Cu" signal "GND4")
		(24 "In11.Cu" signal "IN4")
		(26 "In12.Cu" signal "GND5")
		(28 "In13.Cu" signal "IN5")
		(30 "In14.Cu" signal "GND6")
		(32 "In15.Cu" signal "IN6")
		(34 "In16.Cu" signal "GND7")
		(2 "B.Cu" signal "BOTTOM")
		(9 "F.Adhes" user "F.Adhesive")
		(11 "B.Adhes" user "B.Adhesive")
		(13 "F.Paste" user "Package Geometry/Pastemask Top")
		(15 "B.Paste" user "Package Geometry/Pastemask Bottom")
		(5 "F.SilkS" user "Ref Des/Silkscreen Top")
		(7 "B.SilkS" user "Ref Des/Silkscreen Bottom")
		(1 "F.Mask" user "Board Geometry/Soldermask Top")
		(3 "B.Mask" user "Board Geometry/Soldermask Bottom")
		(17 "Dwgs.User" user "User.Drawings")
		(19 "Cmts.User" user "User.Comments")
		(21 "Eco1.User" user "User.Eco1")
		(23 "Eco2.User" user "User.Eco2")
		(25 "Edge.Cuts" user "Board Geometry/Outline")
		(27 "Margin" user)
		(31 "F.CrtYd" user "Package Geometry/Place Bound Top")
		(29 "B.CrtYd" user "Package Geometry/Place Bound Bottom")
		(35 "F.Fab" user "Ref Des/Assembly Top")
		(33 "B.Fab" user "Ref Des/Assembly Bottom")
	)
	(footprint ""
		(layer "F.Cu")
		(at 367.007902 -172.913802 -90)
		(property "Reference" "PC473_1"
			(at 0 0 270)
			(layer "F.SilkS")
			(hide yes)
			(effects
				(font
					(size 1.27 1.27)
				)
			)
		)
		(property "Value" ""
			(at 0 0 270)
			(layer "F.Fab")
			(effects
				(font
					(size 1.27 1.27)
				)
			)
		)
		(duplicate_pad_numbers_are_jumpers no)
		(fp_line
			(start -0.7874 0.4064)
			(end -0.7874 -0.4064)
			(stroke
				(width 0.1524)
				(type default)
			)
			(layer "F.SilkS")
		)
		(fp_line
			(start 0.7874 0.4064)
			(end -0.7874 0.4064)
			(stroke
				(width 0.1524)
				(type default)
			)
			(layer "F.SilkS")
		)
		(fp_line
			(start -0.7874 -0.4064)
			(end 0.7874 -0.4064)
			(stroke
				(width 0.1524)
				(type default)
			)
			(layer "F.SilkS")
		)
		(fp_line
			(start 0.7874 -0.4064)
			(end 0.7874 0.4064)
			(stroke
				(width 0.1524)
				(type default)
			)
			(layer "F.SilkS")
		)
		(fp_line
			(start -0.67945 0.3048)
			(end -0.67945 -0.305054)
			(stroke
				(width 0.1)
				(type default)
			)
			(layer "F.Fab")
		)
		(fp_line
			(start -0.12065 0.3048)
			(end -0.67945 0.3048)
			(stroke
				(width 0.1)
				(type default)
			)
			(layer "F.Fab")
		)
		(fp_line
			(start 0.120396 0.3048)
			(end 0.120396 0.2794)
			(stroke
				(width 0.1)
				(type default)
			)
			(layer "F.Fab")
		)
		(fp_line
			(start 0.67945 0.3048)
			(end 0.120396 0.3048)
			(stroke
				(width 0.1)
				(type default)
			)
			(layer "F.Fab")
		)
		(fp_line
			(start -0.12065 0.2794)
			(end -0.12065 0.3048)
			(stroke
				(width 0.1)
				(type default)
			)
			(layer "F.Fab")
		)
		(fp_line
			(start 0.120396 0.2794)
			(end -0.12065 0.2794)
			(stroke
				(width 0.1)
				(type default)
			)
			(layer "F.Fab")
		)
		(fp_line
			(start -0.12065 -0.2794)
			(end 0.12065 -0.2794)
			(stroke
				(width 0.1)
				(type default)
			)
			(layer "F.Fab")
		)
		(fp_line
			(start 0.12065 -0.2794)
			(end 0.12065 -0.3048)
			(stroke
				(width 0.1)
				(type default)
			)
			(layer "F.Fab")
		)
		(fp_line
			(start 0.12065 -0.3048)
			(end 0.67945 -0.3048)
			(stroke
				(width 0.1)
				(type default)
			)
			(layer "F.Fab")
		)
		(fp_line
			(start 0.67945 -0.3048)
			(end 0.67945 0.3048)
			(stroke
				(width 0.1)
				(type default)
			)
			(layer "F.Fab")
		)
		(fp_line
			(start -0.67945 -0.305054)
			(end -0.12065 -0.305054)
			(stroke
				(width 0.1)
				(type default)
			)
			(layer "F.Fab")
		)
		(fp_line
			(start -0.12065 -0.305054)
			(end -0.12065 -0.2794)
			(stroke
				(width 0.1)
				(type default)
			)
			(layer "F.Fab")
		)
		(pad "1" smd circle
			(at -0.40005 0 270)
			(size 0 0)
			(layers "F.Cu" "F.Mask" "F.Paste")
			(net "PVDDCR_CPU0_P0_VCCS")
		)
		(pad "2" smd circle
			(at 0.40005 0 270)
			(size 0 0)
			(layers "F.Cu" "F.Mask" "F.Paste")
			(net "GND")
		)
	)
	(footprint ""
		(layer "F.Cu")
		(at 205.234286 -110.649512 180)
		(property "Reference" "R3483"
			(at 0 0 180)
			(layer "F.SilkS")
			(hide yes)
			(effects
				(font
					(size 1.27 1.27)
				)
			)
		)
		(property "Value" ""
			(at 0 0 180)
			(layer "F.Fab")
			(effects
				(font
					(size 1.27 1.27)
				)
			)
		)
		(duplicate_pad_numbers_are_jumpers no)
		(fp_line
			(start 0.7874 0.4064)
			(end -0.7874 0.4064)
			(stroke
				(width 0.1524)
				(type default)
			)
			(layer "F.SilkS")
		)
		(fp_line
			(start 0.7874 -0.4064)
			(end 0.7874 0.4064)
			(stroke
				(width 0.1524)
				(type default)
			)
			(layer "F.SilkS")
		)
		(fp_line
			(start -0.7874 0.4064)
			(end -0.7874 -0.4064)
			(stroke
				(width 0.1524)
				(type default)
			)
			(layer "F.SilkS")
		)
		(fp_line
			(start -0.7874 -0.4064)
			(end 0.7874 -0.4064)
			(stroke
				(width 0.1524)
				(type default)
			)
			(layer "F.SilkS")
		)
		(fp_line
			(start 0.67945 0.3048)
			(end 0.120396 0.3048)
			(stroke
				(width 0.1)
				(type default)
			)
			(layer "F.Fab")
		)
		(fp_line
			(start 0.67945 -0.3048)
			(end 0.67945 0.3048)
			(stroke
				(width 0.1)
				(type default)
			)
			(layer "F.Fab")
		)
		(fp_line
			(start 0.12065 -0.2794)
			(end 0.12065 -0.3048)
			(stroke
				(width 0.1)
				(type default)
			)
			(layer "F.Fab")
		)
		(fp_line
			(start 0.12065 -0.3048)
			(end 0.67945 -0.3048)
			(stroke
				(width 0.1)
				(type default)
			)
			(layer "F.Fab")
		)
		(fp_line
			(start 0.120396 0.3048)
			(end 0.120396 0.2794)
			(stroke
				(width 0.1)
				(type default)
			)
			(layer "F.Fab")
		)
		(fp_line
			(start 0.120396 0.2794)
			(end -0.12065 0.2794)
			(stroke
				(width 0.1)
				(type default)
			)
			(layer "F.Fab")
		)
		(fp_line
			(start -0.12065 0.3048)
			(end -0.67945 0.3048)
			(stroke
				(width 0.1)
				(type default)
			)
			(layer "F.Fab")
		)
		(fp_line
			(start -0.12065 0.2794)
			(end -0.12065 0.3048)
			(stroke
				(width 0.1)
				(type default)
			)
			(layer "F.Fab")
		)
		(fp_line
			(start -0.12065 -0.2794)
			(end 0.12065 -0.2794)
			(stroke
				(width 0.1)
				(type default)
			)
			(layer "F.Fab")
		)
		(fp_line
			(start -0.12065 -0.305054)
			(end -0.12065 -0.2794)
			(stroke
				(width 0.1)
				(type default)
			)
			(layer "F.Fab")
		)
		(fp_line
			(start -0.67945 0.3048)
			(end -0.67945 -0.305054)
			(stroke
				(width 0.1)
				(type default)
			)
			(layer "F.Fab")
		)
		(fp_line
			(start -0.67945 -0.305054)
			(end -0.12065 -0.305054)
			(stroke
				(width 0.1)
				(type default)
			)
			(layer "F.Fab")
		)
		(pad "1" smd circle
			(at -0.40005 0 180)
			(size 0 0)
			(layers "F.Cu" "F.Mask" "F.Paste")
			(net "GPU_FPGA_EROT_RECOV_N")
		)
		(pad "2" smd circle
			(at 0.40005 0 180)
			(size 0 0)
			(layers "F.Cu" "F.Mask" "F.Paste")
			(net "GPU_FPGA_EROT_RECOV_R_N")
		)
	)
)
